# S9S_MB_2U (Grand Teton) — schematic netlist excerpt (pin names and nets, part order shuffled) for the footprints in the layout excerpt that follows; sources: Cadence DE-HDL packaged netlist, KiCad conversion of 03242023_DA0F0TMBIJ0_F0T_Motherboard_J_brd_V01_OCP.brd

PR1653  Q_RES  470 1% CHIP  pkg 0402LF  page 263 : A = P1V8_PCH_AUX ; B = GND
R277  Q_RES  240 1% CHIP  pkg 0402LF  page 119 : A = PVNN_TERM_CPU0 ; B = PU_CPU0_FRMAGENT

(kicad_pcb
	(version 20260206)
	(generator "pcbnew")
	(generator_version "10.0")
	(general
		(thickness 1.6)
		(legacy_teardrops no)
	)
	(paper "A4")
	(title_block
		(title "03242023_DA0F0TMBIJ0_F0T_Motherboard_J_brd_V01_OCP.brd")
		(comment 1 "Grand Teton / footprints 4655-4656 of 6105")
	)
	(layers
		(0 "F.Cu" signal "TOP")
		(4 "In1.Cu" signal "GND")
		(6 "In2.Cu" signal "IN1")
		(8 "In3.Cu" signal "GND1")
		(10 "In4.Cu" signal "IN2")
		(12 "In5.Cu" signal "GND2")
		(14 "In6.Cu" signal "IN3")
		(16 "In7.Cu" signal "GND3")
		(18 "In8.Cu" signal "VCC")
		(20 "In9.Cu" signal "VCC1")
		(22 "In10.Cu" signal "GND4")
		(24 "In11.Cu" signal "IN4")
		(26 "In12.Cu" signal "GND5")
		(28 "In13.Cu" signal "IN5")
		(30 "In14.Cu" signal "GND6")
		(32 "In15.Cu" signal "IN6")
		(34 "In16.Cu" signal "GND7")
		(2 "B.Cu" signal "BOTTOM")
		(9 "F.Adhes" user "F.Adhesive")
		(11 "B.Adhes" user "B.Adhesive")
		(13 "F.Paste" user "Package Geometry/Pastemask Top")
		(15 "B.Paste" user "Package Geometry/Pastemask Bottom")
		(5 "F.SilkS" user "Ref Des/Silkscreen Top")
		(7 "B.SilkS" user "Ref Des/Silkscreen Bottom")
		(1 "F.Mask" user "Board Geometry/Soldermask Top")
		(3 "B.Mask" user "Board Geometry/Soldermask Bottom")
		(17 "Dwgs.User" user "User.Drawings")
		(19 "Cmts.User" user "User.Comments")
		(21 "Eco1.User" user "User.Eco1")
		(23 "Eco2.User" user "User.Eco2")
		(25 "Edge.Cuts" user "Board Geometry/Outline")
		(27 "Margin" user)
		(31 "F.CrtYd" user "Package Geometry/Place Bound Top")
		(29 "B.CrtYd" user "Package Geometry/Place Bound Bottom")
		(35 "F.Fab" user "Ref Des/Assembly Top")
		(33 "B.Fab" user "Ref Des/Assembly Bottom")
	)
	(footprint ""
		(layer "B.Cu")
		(at 321.039998 -188.96711 -90)
		(property "Reference" "R277"
			(at 0 0 90)
			(layer "B.SilkS")
			(hide yes)
			(effects
				(font
					(size 1.27 1.27)
				)
				(justify mirror)
			)
		)
		(property "Value" ""
			(at 0 0 90)
			(layer "B.Fab")
			(effects
				(font
					(size 1.27 1.27)
				)
				(justify mirror)
			)
		)
		(duplicate_pad_numbers_are_jumpers no)
		(fp_line
			(start -0.7874 0.4064)
			(end 0.7874 0.4064)
			(stroke
				(width 0.1524)
				(type default)
			)
			(layer "B.SilkS")
		)
		(fp_line
			(start 0.7874 0.4064)
			(end 0.7874 -0.4064)
			(stroke
				(width 0.1524)
				(type default)
			)
			(layer "B.SilkS")
		)
		(fp_line
			(start -0.7874 -0.4064)
			(end -0.7874 0.4064)
			(stroke
				(width 0.1524)
				(type default)
			)
			(layer "B.SilkS")
		)
		(fp_line
			(start 0.7874 -0.4064)
			(end -0.7874 -0.4064)
			(stroke
				(width 0.1524)
				(type default)
			)
			(layer "B.SilkS")
		)
		(fp_line
			(start -0.67945 0.3048)
			(end -0.120396 0.3048)
			(stroke
				(width 0.1)
				(type default)
			)
			(layer "B.Fab")
		)
		(fp_line
			(start -0.120396 0.3048)
			(end -0.120396 0.2794)
			(stroke
				(width 0.1)
				(type default)
			)
			(layer "B.Fab")
		)
		(fp_line
			(start 0.12065 0.3048)
			(end 0.67945 0.3048)
			(stroke
				(width 0.1)
				(type default)
			)
			(layer "B.Fab")
		)
		(fp_line
			(start 0.67945 0.3048)
			(end 0.67945 -0.305054)
			(stroke
				(width 0.1)
				(type default)
			)
			(layer "B.Fab")
		)
		(fp_line
			(start -0.120396 0.2794)
			(end 0.12065 0.2794)
			(stroke
				(width 0.1)
				(type default)
			)
			(layer "B.Fab")
		)
		(fp_line
			(start 0.12065 0.2794)
			(end 0.12065 0.3048)
			(stroke
				(width 0.1)
				(type default)
			)
			(layer "B.Fab")
		)
		(fp_line
			(start -0.12065 -0.2794)
			(end -0.12065 -0.3048)
			(stroke
				(width 0.1)
				(type default)
			)
			(layer "B.Fab")
		)
		(fp_line
			(start 0.12065 -0.2794)
			(end -0.12065 -0.2794)
			(stroke
				(width 0.1)
				(type default)
			)
			(layer "B.Fab")
		)
		(fp_line
			(start -0.67945 -0.3048)
			(end -0.67945 0.3048)
			(stroke
				(width 0.1)
				(type default)
			)
			(layer "B.Fab")
		)
		(fp_line
			(start -0.12065 -0.3048)
			(end -0.67945 -0.3048)
			(stroke
				(width 0.1)
				(type default)
			)
			(layer "B.Fab")
		)
		(fp_line
			(start 0.12065 -0.305054)
			(end 0.12065 -0.2794)
			(stroke
				(width 0.1)
				(type default)
			)
			(layer "B.Fab")
		)
		(fp_line
			(start 0.67945 -0.305054)
			(end 0.12065 -0.305054)
			(stroke
				(width 0.1)
				(type default)
			)
			(layer "B.Fab")
		)
		(pad "1" smd circle
			(at 0.40005 0 90)
			(size 0 0)
			(layers "B.Cu" "B.Mask" "B.Paste")
			(net "PVNN_TERM_CPU0")
		)
		(pad "2" smd circle
			(at -0.40005 0 90)
			(size 0 0)
			(layers "B.Cu" "B.Mask" "B.Paste")
			(net "PU_CPU0_FRMAGENT")
		)
	)
	(footprint ""
		(layer "B.Cu")
		(at 376.694446 -78.551278 180)
		(property "Reference" "PR1653"
			(at 0 0 0)
			(layer "B.SilkS")
			(hide yes)
			(effects
				(font
					(size 1.27 1.27)
				)
				(justify mirror)
			)
		)
		(property "Value" ""
			(at 0 0 0)
			(layer "B.Fab")
			(effects
				(font
					(size 1.27 1.27)
				)
				(justify mirror)
			)
		)
		(duplicate_pad_numbers_are_jumpers no)
		(fp_line
			(start 0.7874 0.4064)
			(end 0.7874 -0.4064)
			(stroke
				(width 0.1524)
				(type default)
			)
			(layer "B.SilkS")
		)
		(fp_line
			(start 0.7874 -0.4064)
			(end -0.7874 -0.4064)
			(stroke
				(width 0.1524)
				(type default)
			)
			(layer "B.SilkS")
		)
		(fp_line
			(start -0.7874 0.4064)
			(end 0.7874 0.4064)
			(stroke
				(width 0.1524)
				(type default)
			)
			(layer "B.SilkS")
		)
		(fp_line
			(start -0.7874 -0.4064)
			(end -0.7874 0.4064)
			(stroke
				(width 0.1524)
				(type default)
			)
			(layer "B.SilkS")
		)
		(fp_line
			(start 0.67945 0.3048)
			(end 0.67945 -0.305054)
			(stroke
				(width 0.1)
				(type default)
			)
			(layer "B.Fab")
		)
		(fp_line
			(start 0.67945 -0.305054)
			(end 0.12065 -0.305054)
			(stroke
				(width 0.1)
				(type default)
			)
			(layer "B.Fab")
		)
		(fp_line
			(start 0.12065 0.3048)
			(end 0.67945 0.3048)
			(stroke
				(width 0.1)
				(type default)
			)
			(layer "B.Fab")
		)
		(fp_line
			(start 0.12065 0.2794)
			(end 0.12065 0.3048)
			(stroke
				(width 0.1)
				(type default)
			)
			(layer "B.Fab")
		)
		(fp_line
			(start 0.12065 -0.2794)
			(end -0.12065 -0.2794)
			(stroke
				(width 0.1)
				(type default)
			)
			(layer "B.Fab")
		)
		(fp_line
			(start 0.12065 -0.305054)
			(end 0.12065 -0.2794)
			(stroke
				(width 0.1)
				(type default)
			)
			(layer "B.Fab")
		)
		(fp_line
			(start -0.120396 0.3048)
			(end -0.120396 0.2794)
			(stroke
				(width 0.1)
				(type default)
			)
			(layer "B.Fab")
		)
		(fp_line
			(start -0.120396 0.2794)
			(end 0.12065 0.2794)
			(stroke
				(width 0.1)
				(type default)
			)
			(layer "B.Fab")
		)
		(fp_line
			(start -0.12065 -0.2794)
			(end -0.12065 -0.3048)
			(stroke
				(width 0.1)
				(type default)
			)
			(layer "B.Fab")
		)
		(fp_line
			(start -0.12065 -0.3048)
			(end -0.67945 -0.3048)
			(stroke
				(width 0.1)
				(type default)
			)
			(layer "B.Fab")
		)
		(fp_line
			(start -0.67945 0.3048)
			(end -0.120396 0.3048)
			(stroke
				(width 0.1)
				(type default)
			)
			(layer "B.Fab")
		)
		(fp_line
			(start -0.67945 -0.3048)
			(end -0.67945 0.3048)
			(stroke
				(width 0.1)
				(type default)
			)
			(layer "B.Fab")
		)
		(pad "1" smd circle
			(at 0.40005 0)
			(size 0 0)
			(layers "B.Cu" "B.Mask" "B.Paste")
			(net "P1V8_PCH_AUX")
		)
		(pad "2" smd circle
			(at -0.40005 0)
			(size 0 0)
			(layers "B.Cu" "B.Mask" "B.Paste")
			(net "GND")
		)
	)
)
